# SCM (Grand Teton) — schematic netlist excerpt (pin names and nets, part order shuffled) for the footprints in the layout excerpt that follows; sources: Cadence DE-HDL packaged netlist, KiCad conversion of 12092022_DA0F0TMDCD0_F0T_Management_Board_D_brd_V3_OCP.brd

R65  Q_RES  33.2 1% CHIP  pkg 0402LF  page 13 : A = BMC_CPLD_GPIO_2_R1 ; B = BMC_CPLD_GPIO_2
R114  Q_RES  0 5% CHIP  pkg 0402LF  page 36 : A = SMB_BMC_MM16_R4_SDA ; B = SMB_BMC_MM16_R5_SDA

(kicad_pcb
	(version 20260206)
	(generator "pcbnew")
	(generator_version "10.0")
	(general
		(thickness 1.6)
		(legacy_teardrops no)
	)
	(paper "A4")
	(title_block
		(title "12092022_DA0F0TMDCD0_F0T_Management_Board_D_brd_V3_OCP.brd")
		(comment 1 "Grand Teton / footprints 101-102 of 1440")
	)
	(layers
		(0 "F.Cu" signal "TOP")
		(4 "In1.Cu" signal "GND")
		(6 "In2.Cu" signal "IN1")
		(8 "In3.Cu" signal "GND1")
		(10 "In4.Cu" signal "IN2")
		(12 "In5.Cu" signal "VCC")
		(14 "In6.Cu" signal "VCC1")
		(16 "In7.Cu" signal "IN3")
		(18 "In8.Cu" signal "GND2")
		(20 "In9.Cu" signal "IN4")
		(22 "In10.Cu" signal "GND3")
		(2 "B.Cu" signal "BOTTOM")
		(9 "F.Adhes" user "F.Adhesive")
		(11 "B.Adhes" user "B.Adhesive")
		(13 "F.Paste" user "Package Geometry/Pastemask Top")
		(15 "B.Paste" user "Package Geometry/Pastemask Bottom")
		(5 "F.SilkS" user "Ref Des/Silkscreen Top")
		(7 "B.SilkS" user "Ref Des/Silkscreen Bottom")
		(1 "F.Mask" user "Board Geometry/Soldermask Top")
		(3 "B.Mask" user "Board Geometry/Soldermask Bottom")
		(17 "Dwgs.User" user "User.Drawings")
		(19 "Cmts.User" user "User.Comments")
		(21 "Eco1.User" user "User.Eco1")
		(23 "Eco2.User" user "User.Eco2")
		(25 "Edge.Cuts" user "Board Geometry/Outline")
		(27 "Margin" user)
		(31 "F.CrtYd" user "Package Geometry/Place Bound Top")
		(29 "B.CrtYd" user "Package Geometry/Place Bound Bottom")
		(35 "F.Fab" user "Ref Des/Assembly Top")
		(33 "B.Fab" user "Ref Des/Assembly Bottom")
	)
	(footprint ""
		(layer "F.Cu")
		(at 35.941 -60.96 90)
		(property "Reference" "R65"
			(at 0 0 90)
			(layer "F.SilkS")
			(hide yes)
			(effects
				(font
					(size 1.27 1.27)
				)
			)
		)
		(property "Value" ""
			(at 0 0 90)
			(layer "F.Fab")
			(effects
				(font
					(size 1.27 1.27)
				)
			)
		)
		(duplicate_pad_numbers_are_jumpers no)
		(fp_line
			(start 0.7874 -0.4064)
			(end 0.7874 0.4064)
			(stroke
				(width 0.1524)
				(type default)
			)
			(layer "F.SilkS")
		)
		(fp_line
			(start -0.7874 -0.4064)
			(end 0.7874 -0.4064)
			(stroke
				(width 0.1524)
				(type default)
			)
			(layer "F.SilkS")
		)
		(fp_line
			(start 0.7874 0.4064)
			(end -0.7874 0.4064)
			(stroke
				(width 0.1524)
				(type default)
			)
			(layer "F.SilkS")
		)
		(fp_line
			(start -0.7874 0.4064)
			(end -0.7874 -0.4064)
			(stroke
				(width 0.1524)
				(type default)
			)
			(layer "F.SilkS")
		)
		(fp_line
			(start -0.12065 -0.305054)
			(end -0.12065 -0.2794)
			(stroke
				(width 0.1)
				(type default)
			)
			(layer "F.Fab")
		)
		(fp_line
			(start -0.67945 -0.305054)
			(end -0.12065 -0.305054)
			(stroke
				(width 0.1)
				(type default)
			)
			(layer "F.Fab")
		)
		(fp_line
			(start 0.67945 -0.3048)
			(end 0.67945 0.3048)
			(stroke
				(width 0.1)
				(type default)
			)
			(layer "F.Fab")
		)
		(fp_line
			(start 0.12065 -0.3048)
			(end 0.67945 -0.3048)
			(stroke
				(width 0.1)
				(type default)
			)
			(layer "F.Fab")
		)
		(fp_line
			(start 0.12065 -0.2794)
			(end 0.12065 -0.3048)
			(stroke
				(width 0.1)
				(type default)
			)
			(layer "F.Fab")
		)
		(fp_line
			(start -0.12065 -0.2794)
			(end 0.12065 -0.2794)
			(stroke
				(width 0.1)
				(type default)
			)
			(layer "F.Fab")
		)
		(fp_line
			(start 0.120396 0.2794)
			(end -0.12065 0.2794)
			(stroke
				(width 0.1)
				(type default)
			)
			(layer "F.Fab")
		)
		(fp_line
			(start -0.12065 0.2794)
			(end -0.12065 0.3048)
			(stroke
				(width 0.1)
				(type default)
			)
			(layer "F.Fab")
		)
		(fp_line
			(start 0.67945 0.3048)
			(end 0.120396 0.3048)
			(stroke
				(width 0.1)
				(type default)
			)
			(layer "F.Fab")
		)
		(fp_line
			(start 0.120396 0.3048)
			(end 0.120396 0.2794)
			(stroke
				(width 0.1)
				(type default)
			)
			(layer "F.Fab")
		)
		(fp_line
			(start -0.12065 0.3048)
			(end -0.67945 0.3048)
			(stroke
				(width 0.1)
				(type default)
			)
			(layer "F.Fab")
		)
		(fp_line
			(start -0.67945 0.3048)
			(end -0.67945 -0.305054)
			(stroke
				(width 0.1)
				(type default)
			)
			(layer "F.Fab")
		)
		(pad "1" smd circle
			(at -0.40005 0 90)
			(size 0 0)
			(layers "F.Cu" "F.Mask" "F.Paste")
			(net "BMC_CPLD_GPIO_2_R1")
		)
		(pad "2" smd circle
			(at 0.40005 0 90)
			(size 0 0)
			(layers "F.Cu" "F.Mask" "F.Paste")
			(net "BMC_CPLD_GPIO_2")
		)
	)
	(footprint ""
		(layer "F.Cu")
		(at 18.034 -102.743 90)
		(property "Reference" "R114"
			(at 0 0 90)
			(layer "F.SilkS")
			(hide yes)
			(effects
				(font
					(size 1.27 1.27)
				)
			)
		)
		(property "Value" ""
			(at 0 0 90)
			(layer "F.Fab")
			(effects
				(font
					(size 1.27 1.27)
				)
			)
		)
		(duplicate_pad_numbers_are_jumpers no)
		(fp_line
			(start 0.7874 -0.4064)
			(end 0.7874 0.4064)
			(stroke
				(width 0.1524)
				(type default)
			)
			(layer "F.SilkS")
		)
		(fp_line
			(start -0.7874 -0.4064)
			(end 0.7874 -0.4064)
			(stroke
				(width 0.1524)
				(type default)
			)
			(layer "F.SilkS")
		)
		(fp_line
			(start 0.7874 0.4064)
			(end -0.7874 0.4064)
			(stroke
				(width 0.1524)
				(type default)
			)
			(layer "F.SilkS")
		)
		(fp_line
			(start -0.7874 0.4064)
			(end -0.7874 -0.4064)
			(stroke
				(width 0.1524)
				(type default)
			)
			(layer "F.SilkS")
		)
		(fp_line
			(start -0.12065 -0.305054)
			(end -0.12065 -0.2794)
			(stroke
				(width 0.1)
				(type default)
			)
			(layer "F.Fab")
		)
		(fp_line
			(start -0.67945 -0.305054)
			(end -0.12065 -0.305054)
			(stroke
				(width 0.1)
				(type default)
			)
			(layer "F.Fab")
		)
		(fp_line
			(start 0.67945 -0.3048)
			(end 0.67945 0.3048)
			(stroke
				(width 0.1)
				(type default)
			)
			(layer "F.Fab")
		)
		(fp_line
			(start 0.12065 -0.3048)
			(end 0.67945 -0.3048)
			(stroke
				(width 0.1)
				(type default)
			)
			(layer "F.Fab")
		)
		(fp_line
			(start 0.12065 -0.2794)
			(end 0.12065 -0.3048)
			(stroke
				(width 0.1)
				(type default)
			)
			(layer "F.Fab")
		)
		(fp_line
			(start -0.12065 -0.2794)
			(end 0.12065 -0.2794)
			(stroke
				(width 0.1)
				(type default)
			)
			(layer "F.Fab")
		)
		(fp_line
			(start 0.120396 0.2794)
			(end -0.12065 0.2794)
			(stroke
				(width 0.1)
				(type default)
			)
			(layer "F.Fab")
		)
		(fp_line
			(start -0.12065 0.2794)
			(end -0.12065 0.3048)
			(stroke
				(width 0.1)
				(type default)
			)
			(layer "F.Fab")
		)
		(fp_line
			(start 0.67945 0.3048)
			(end 0.120396 0.3048)
			(stroke
				(width 0.1)
				(type default)
			)
			(layer "F.Fab")
		)
		(fp_line
			(start 0.120396 0.3048)
			(end 0.120396 0.2794)
			(stroke
				(width 0.1)
				(type default)
			)
			(layer "F.Fab")
		)
		(fp_line
			(start -0.12065 0.3048)
			(end -0.67945 0.3048)
			(stroke
				(width 0.1)
				(type default)
			)
			(layer "F.Fab")
		)
		(fp_line
			(start -0.67945 0.3048)
			(end -0.67945 -0.305054)
			(stroke
				(width 0.1)
				(type default)
			)
			(layer "F.Fab")
		)
		(pad "1" smd circle
			(at -0.40005 0 90)
			(size 0 0)
			(layers "F.Cu" "F.Mask" "F.Paste")
			(net "SMB_BMC_MM16_R4_SDA")
		)
		(pad "2" smd circle
			(at 0.40005 0 90)
			(size 0 0)
			(layers "F.Cu" "F.Mask" "F.Paste")
			(net "SMB_BMC_MM16_R5_SDA")
		)
	)
)
